# TIMECARD (Time Appliance Project (Time Card)) — schematic netlist excerpt (pin names and nets, part order shuffled) for the footprints in the layout excerpt that follows; sources: Cadence DE-HDL packaged netlist, KiCad conversion of R4006-B0001-02_R01.brd

SP40  SOLDER_PREFORM  pkg 0201_SOLDER_PREFORM_4MIL  page 34 : \1\ = NC ; \2\ = NC
R186  RESISTOR  3KOHM 1%  pkg SMC_0402R_H016  page 30 : \1\ = SG ; \2\ = XP1R2V_FB
R287  RESISTOR  4.7KOHM 1%  pkg SMC_0402R_H016  page 21 : \1\ = FPGA_IN_MAC_ALARM_OUT_N ; \2\ = XP3R3V_FPGA

(kicad_pcb
	(version 20260206)
	(generator "pcbnew")
	(generator_version "10.0")
	(general
		(thickness 1.6)
		(legacy_teardrops no)
	)
	(paper "A4")
	(title_block
		(title "timecard-production-celestica-r4006 — R4006-B0001-02_R01.brd")
		(comment 1 "Time Appliance Project (Time Card) / footprints 410-412 of 1113")
	)
	(layers
		(0 "F.Cu" signal "TOP")
		(4 "In1.Cu" signal "L02_GND1")
		(6 "In2.Cu" signal "L03_SIG1")
		(8 "In3.Cu" signal "L04_GND2")
		(10 "In4.Cu" signal "L05_VCC1")
		(12 "In5.Cu" signal "L06_VCC2")
		(14 "In6.Cu" signal "L07_GND3")
		(16 "In7.Cu" signal "L08_SIG2")
		(18 "In8.Cu" signal "L09_GND4")
		(2 "B.Cu" signal "BOTTOM")
		(9 "F.Adhes" user "F.Adhesive")
		(11 "B.Adhes" user "B.Adhesive")
		(13 "F.Paste" user "Package Geometry/Pastemask Top")
		(15 "B.Paste" user "Package Geometry/Pastemask Bottom")
		(5 "F.SilkS" user "Ref Des/Silkscreen Top")
		(7 "B.SilkS" user "Ref Des/Silkscreen Bottom")
		(1 "F.Mask" user "Board Geometry/Soldermask Top")
		(3 "B.Mask" user "Board Geometry/Soldermask Bottom")
		(17 "Dwgs.User" user "User.Drawings")
		(19 "Cmts.User" user "User.Comments")
		(21 "Eco1.User" user "User.Eco1")
		(23 "Eco2.User" user "User.Eco2")
		(25 "Edge.Cuts" user "Board Geometry/Outline")
		(27 "Margin" user)
		(31 "F.CrtYd" user "Package Geometry/Place Bound Top")
		(29 "B.CrtYd" user "Package Geometry/Place Bound Bottom")
		(35 "F.Fab" user "Ref Des/Assembly Top")
		(33 "B.Fab" user "Ref Des/Assembly Bottom")
	)
	(footprint ""
		(layer "F.Cu")
		(at 79.883 -41.783 180)
		(property "Reference" "R287"
			(at -0.381 -13.88237 0)
			(unlocked yes)
			(layer "F.SilkS")
			(effects
				(font
					(size 0.7874 0.5842)
					(thickness 0.1524)
				)
			)
		)
		(property "Value" "VAL*"
			(at 0.02032 2.13233 180)
			(unlocked yes)
			(layer "F.Fab")
			(hide yes)
			(effects
				(font
					(size 0.7874 0.5842)
					(thickness 0.1524)
				)
			)
		)
		(property "Device Type" "RESISTOR-G155-14701-01,4.7KOHMA"
			(at 0.008382 1.210564 180)
			(unlocked yes)
			(layer "F.Fab")
			(hide yes)
			(effects
				(font
					(size 0.7874 0.5842)
					(thickness 0.1524)
				)
			)
		)
		(property "User Part Number" "PARTNUM*"
			(at 0.02032 4.024884 180)
			(unlocked yes)
			(layer "Cmts.User")
			(hide yes)
			(effects
				(font
					(size 0.7874 0.5842)
					(thickness 0.1524)
				)
			)
		)
		(property "Tolerance" "TOL*"
			(at 0.044704 3.05435 180)
			(unlocked yes)
			(layer "Cmts.User")
			(hide yes)
			(effects
				(font
					(size 0.7874 0.5842)
					(thickness 0.1524)
				)
			)
		)
		(duplicate_pad_numbers_are_jumpers no)
		(fp_line
			(start 1.143 0.5588)
			(end 1.143 -0.5588)
			(stroke
				(width 0.1)
				(type default)
			)
			(layer "F.SilkS")
		)
		(fp_line
			(start 1.143 -0.5588)
			(end -1.143 -0.5588)
			(stroke
				(width 0.1)
				(type default)
			)
			(layer "F.SilkS")
		)
		(fp_line
			(start -1.143 0.5588)
			(end 1.143 0.5588)
			(stroke
				(width 0.1)
				(type default)
			)
			(layer "F.SilkS")
		)
		(fp_line
			(start -1.143 -0.5588)
			(end -1.143 0.5588)
			(stroke
				(width 0.1)
				(type default)
			)
			(layer "F.SilkS")
		)
		(fp_rect
			(start 1.143 -0.5588)
			(end -1.143 0.5588)
			(stroke
				(width 0)
				(type default)
			)
			(fill no)
			(layer "F.CrtYd")
		)
		(fp_line
			(start 0.508 0.3048)
			(end 0.508 -0.3048)
			(stroke
				(width 0.1)
				(type default)
			)
			(layer "F.Fab")
		)
		(fp_line
			(start 0.508 -0.3048)
			(end -0.508 -0.3048)
			(stroke
				(width 0.1)
				(type default)
			)
			(layer "F.Fab")
		)
		(fp_line
			(start -0.508 0.3048)
			(end 0.508 0.3048)
			(stroke
				(width 0.1)
				(type default)
			)
			(layer "F.Fab")
		)
		(fp_line
			(start -0.508 -0.3048)
			(end -0.508 0.3048)
			(stroke
				(width 0.1)
				(type default)
			)
			(layer "F.Fab")
		)
		(pad "1" smd rect
			(at -0.5334 0 180)
			(size 0.7112 0.6096)
			(layers "F.Cu" "F.Mask" "F.Paste")
			(net "FPGA_IN_MAC_ALARM_OUT_N")
		)
		(pad "2" smd rect
			(at 0.5334 0 180)
			(size 0.7112 0.6096)
			(layers "F.Cu" "F.Mask" "F.Paste")
			(net "XP3R3V_FPGA")
		)
		(zone
			(layer "F.Cu")
			(hatch none 0.5)
			(connect_pads
				(clearance 0)
			)
			(min_thickness 0.25)
			(keepout
				(tracks allowed)
				(vias not_allowed)
				(pads allowed)
				(copperpour not_allowed)
				(footprints allowed)
			)
			(placement
				(enabled no)
				(sheetname "")
			)
			(fill
				(thermal_gap 0.5)
				(thermal_bridge_width 0.5)
				(island_removal_mode 0)
			)
			(polygon
				(pts
					(xy 79.8068 -41.4782) (xy 79.9592 -41.4782) (xy 79.9592 -42.0878) (xy 79.8068 -42.0878)
				)
			)
		)
	)
	(footprint ""
		(layer "F.Cu")
		(at 70.485 -132.207)
		(property "Reference" "SP40"
			(at 0 0 0)
			(layer "F.SilkS")
			(hide yes)
			(effects
				(font
					(size 1.27 1.27)
				)
			)
		)
		(property "Value" ""
			(at 0 0 0)
			(layer "F.Fab")
			(effects
				(font
					(size 1.27 1.27)
				)
			)
		)
		(duplicate_pad_numbers_are_jumpers no)
	)
	(footprint ""
		(layer "F.Cu")
		(at 97.4598 -68.072)
		(property "Reference" "R186"
			(at -28.067 -19.014694 0)
			(unlocked yes)
			(layer "F.SilkS")
			(effects
				(font
					(size 0.7874 0.5842)
					(thickness 0.1524)
				)
			)
		)
		(property "Value" "VAL*"
			(at 0.02032 2.13233 0)
			(unlocked yes)
			(layer "F.Fab")
			(hide yes)
			(effects
				(font
					(size 0.7874 0.5842)
					(thickness 0.1524)
				)
			)
		)
		(property "Tolerance" "TOL*"
			(at 0.044704 3.05435 0)
			(unlocked yes)
			(layer "Cmts.User")
			(hide yes)
			(effects
				(font
					(size 0.7874 0.5842)
					(thickness 0.1524)
				)
			)
		)
		(property "User Part Number" "PARTNUM*"
			(at 0.02032 4.024884 0)
			(unlocked yes)
			(layer "Cmts.User")
			(hide yes)
			(effects
				(font
					(size 0.7874 0.5842)
					(thickness 0.1524)
				)
			)
		)
		(property "Device Type" "RESISTOR-G155-03001-01,3KOHM,1%"
			(at 0.008382 1.210564 0)
			(unlocked yes)
			(layer "F.Fab")
			(hide yes)
			(effects
				(font
					(size 0.7874 0.5842)
					(thickness 0.1524)
				)
			)
		)
		(duplicate_pad_numbers_are_jumpers no)
		(fp_line
			(start -1.143 -0.5588)
			(end -1.143 0.5588)
			(stroke
				(width 0.1)
				(type default)
			)
			(layer "F.SilkS")
		)
		(fp_line
			(start -1.143 0.5588)
			(end 1.143 0.5588)
			(stroke
				(width 0.1)
				(type default)
			)
			(layer "F.SilkS")
		)
		(fp_line
			(start 1.143 -0.5588)
			(end -1.143 -0.5588)
			(stroke
				(width 0.1)
				(type default)
			)
			(layer "F.SilkS")
		)
		(fp_line
			(start 1.143 0.5588)
			(end 1.143 -0.5588)
			(stroke
				(width 0.1)
				(type default)
			)
			(layer "F.SilkS")
		)
		(fp_poly
			(pts
				(xy -1.143 0.5588) (xy 1.143 0.5588) (xy 1.143 -0.5588) (xy -1.143 -0.5588)
			)
			(stroke
				(width 0)
				(type default)
			)
			(fill no)
			(layer "F.CrtYd")
		)
		(fp_line
			(start -0.508 -0.3048)
			(end -0.508 0.3048)
			(stroke
				(width 0.1)
				(type default)
			)
			(layer "F.Fab")
		)
		(fp_line
			(start -0.508 0.3048)
			(end 0.508 0.3048)
			(stroke
				(width 0.1)
				(type default)
			)
			(layer "F.Fab")
		)
		(fp_line
			(start 0.508 -0.3048)
			(end -0.508 -0.3048)
			(stroke
				(width 0.1)
				(type default)
			)
			(layer "F.Fab")
		)
		(fp_line
			(start 0.508 0.3048)
			(end 0.508 -0.3048)
			(stroke
				(width 0.1)
				(type default)
			)
			(layer "F.Fab")
		)
		(pad "1" smd rect
			(at -0.5334 0)
			(size 0.7112 0.6096)
			(layers "F.Cu" "F.Mask" "F.Paste")
			(net "SG")
		)
		(pad "2" smd rect
			(at 0.5334 0)
			(size 0.7112 0.6096)
			(layers "F.Cu" "F.Mask" "F.Paste")
			(net "XP1R2V_FB")
		)
		(zone
			(layer "F.Cu")
			(hatch none 0.5)
			(connect_pads
				(clearance 0)
			)
			(min_thickness 0.25)
			(keepout
				(tracks not_allowed)
				(vias allowed)
				(pads allowed)
				(copperpour not_allowed)
				(footprints allowed)
			)
			(placement
				(enabled no)
				(sheetname "")
			)
			(fill
				(thermal_gap 0.5)
				(thermal_bridge_width 0.5)
				(island_removal_mode 0)
			)
			(polygon
				(pts
					(xy 97.3836 -67.7672) (xy 97.536 -67.7672) (xy 97.536 -68.3768) (xy 97.3836 -68.3768)
				)
			)
		)
		(zone
			(layer "F.Cu")
			(hatch none 0.5)
			(connect_pads
				(clearance 0)
			)
			(min_thickness 0.25)
			(keepout
				(tracks allowed)
				(vias not_allowed)
				(pads allowed)
				(copperpour not_allowed)
				(footprints allowed)
			)
			(placement
				(enabled no)
				(sheetname "")
			)
			(fill
				(thermal_gap 0.5)
				(thermal_bridge_width 0.5)
				(island_removal_mode 0)
			)
			(polygon
				(pts
					(xy 97.3836 -67.7672) (xy 97.536 -67.7672) (xy 97.536 -68.3768) (xy 97.3836 -68.3768)
				)
			)
		)
	)
)
